(kicad_pcb
	(version 20241229)
	(generator "pcbnew")
	(generator_version "9.0")
	(general
		(thickness 1.711)
		(legacy_teardrops no)
	)
	(paper "A4")
	(title_block
		(title "Antmicro Baseboard for Jetson AGX Thor")
		(date "2026-02-18")
		(rev "1.1.0")
		(company "Antmicro Ltd")
		(comment 1 "www.antmicro.com")
		(comment 9 "footprints 458-461 of 1170")
	)
	(layers
		(0 "F.Cu" signal)
		(4 "In1.Cu" signal)
		(6 "In2.Cu" signal)
		(8 "In3.Cu" signal)
		(10 "In4.Cu" jumper)
		(12 "In5.Cu" signal)
		(14 "In6.Cu" signal)
		(16 "In7.Cu" signal)
		(18 "In8.Cu" signal)
		(2 "B.Cu" signal)
		(9 "F.Adhes" user "F.Adhesive")
		(11 "B.Adhes" user "B.Adhesive")
		(13 "F.Paste" user)
		(15 "B.Paste" user)
		(5 "F.SilkS" user "F.Silkscreen")
		(7 "B.SilkS" user "B.Silkscreen")
		(1 "F.Mask" user)
		(3 "B.Mask" user)
		(17 "Dwgs.User" user "User.Drawings")
		(19 "Cmts.User" user "User.Comments")
		(21 "Eco1.User" user "User.Eco1")
		(23 "Eco2.User" user "User.Eco2")
		(25 "Edge.Cuts" user)
		(27 "Margin" user)
		(31 "F.CrtYd" user "F.Courtyard")
		(29 "B.CrtYd" user "B.Courtyard")
		(35 "F.Fab" user)
		(33 "B.Fab" user)
	)
	(footprint "antmicro-footprints:USON-10_2.5x1mm_P0.5mm"
		(layer "F.Cu")
		(at 220.815 117.625 180)
		(descr "USON-10 2.5x1mm_ Pitch 0.5mm")
		(tags "USON-10 2.5x1mm Pitch 0.5mm")
		(property "Reference" "U24"
			(at -0.995 1.095 90)
			(layer "F.SilkS")
			(effects
				(font
					(size 0.7 0.7)
					(thickness 0.15)
				)
				(justify right top)
			)
		)
		(property "Value" "TPD4E05U06QDQARQ1"
			(at 0.018 2.499 0)
			(layer "F.Fab")
			(effects
				(font
					(size 0.7 0.7)
					(thickness 0.15)
				)
				(justify right top)
			)
		)
		(property "Datasheet" "https://www.ti.com/lit/ds/symlink/tpd4e05u06-q1.pdf?HQS=dis-mous-null-mousermode-dsf-pf-null-wwe&ts=1663591265741&ref_url=https%253A%252F%252Fwww.mouser.com%252F"
			(at 0 0 0)
			(layer "F.Fab")
			(hide yes)
			(effects
				(font
					(size 1.27 1.27)
					(thickness 0.15)
				)
			)
		)
		(property "Description" "TVS diode array, 12 kV, USON-10, 5.5 V, 0.5 pF"
			(at 0 0 0)
			(layer "F.Fab")
			(hide yes)
			(effects
				(font
					(size 1.27 1.27)
					(thickness 0.15)
				)
			)
		)
		(property "Manufacturer" "Texas Instruments"
			(at 0 0 180)
			(unlocked yes)
			(layer "F.Fab")
			(hide yes)
			(effects
				(font
					(size 1 1)
					(thickness 0.15)
				)
			)
		)
		(property "MPN" "TPD4E05U06QDQARQ1"
			(at 0 0 180)
			(unlocked yes)
			(layer "F.Fab")
			(hide yes)
			(effects
				(font
					(size 1 1)
					(thickness 0.15)
				)
			)
		)
		(property "Author" "Antmicro"
			(at 0 0 180)
			(unlocked yes)
			(layer "F.Fab")
			(hide yes)
			(effects
				(font
					(size 1 1)
					(thickness 0.15)
				)
			)
		)
		(property "License" "Apache-2.0"
			(at 0 0 180)
			(unlocked yes)
			(layer "F.Fab")
			(hide yes)
			(effects
				(font
					(size 1 1)
					(thickness 0.15)
				)
			)
		)
		(sheetname "/USB Hub/")
		(sheetfile "usb_hub.kicad_sch")
		(attr smd)
		(fp_line
			(start 0.498 1.398)
			(end -0.5 1.398)
			(stroke
				(width 0.15)
				(type solid)
			)
			(layer "F.SilkS")
		)
		(fp_line
			(start 0.498 -1.401)
			(end -0.5 -1.401)
			(stroke
				(width 0.15)
				(type solid)
			)
			(layer "F.SilkS")
		)
		(fp_circle
			(center -0.68 -1.27)
			(end -0.63 -1.27)
			(stroke
				(width 0.15)
				(type solid)
			)
			(fill yes)
			(layer "F.SilkS")
		)
		(fp_rect
			(start -0.8 -1.5)
			(end 0.8 1.499)
			(stroke
				(width 0.05)
				(type solid)
			)
			(fill no)
			(layer "F.CrtYd")
		)
		(fp_line
			(start 0.498 -1.25)
			(end 0.498 1.249)
			(stroke
				(width 0.15)
				(type solid)
			)
			(layer "F.Fab")
		)
		(fp_line
			(start 0.498 -1.25)
			(end -0.25 -1.25)
			(stroke
				(width 0.15)
				(type solid)
			)
			(layer "F.Fab")
		)
		(fp_line
			(start -0.25 -1.25)
			(end -0.5 -1)
			(stroke
				(width 0.15)
				(type solid)
			)
			(layer "F.Fab")
		)
		(fp_line
			(start -0.5 1.249)
			(end 0.498 1.249)
			(stroke
				(width 0.15)
				(type solid)
			)
			(layer "F.Fab")
		)
		(fp_line
			(start -0.5 -1)
			(end -0.5 1.249)
			(stroke
				(width 0.15)
				(type solid)
			)
			(layer "F.Fab")
		)
		(fp_text user "License: Apache-2.0"
			(at -0.802 6.9 0)
			(layer "F.Fab")
			(effects
				(font
					(size 0.7 0.7)
					(thickness 0.15)
				)
				(justify right top)
			)
		)
		(fp_text user "Author: Antmicro"
			(at -0.802 5.7 0)
			(layer "F.Fab")
			(effects
				(font
					(size 0.7 0.7)
					(thickness 0.15)
				)
				(justify right top)
			)
		)
		(fp_text user "${REFERENCE}"
			(at -0.802 4.498 0)
			(layer "F.Fab")
			(effects
				(font
					(size 0.7 0.7)
					(thickness 0.15)
				)
				(justify right top)
			)
		)
		(pad "1" smd roundrect
			(at -0.387 -1 90)
			(size 0.25 0.55)
			(layers "F.Cu" "F.Mask" "F.Paste")
			(roundrect_rratio 0.25)
			(net 95 "/USB Hub/USBC3_CONN_TX1_N")
			(pintype "passive")
		)
		(pad "2" smd roundrect
			(at -0.387 -0.5 90)
			(size 0.25 0.55)
			(layers "F.Cu" "F.Mask" "F.Paste")
			(roundrect_rratio 0.25)
			(net 164 "/USB Hub/USBC3_CONN_TX1_P")
			(pintype "passive")
		)
		(pad "3" smd roundrect
			(at -0.387 0 90)
			(size 0.4 0.55)
			(layers "F.Cu" "F.Mask" "F.Paste")
			(roundrect_rratio 0.25)
			(net 1 "GND")
			(pintype "power_in")
		)
		(pad "4" smd roundrect
			(at -0.387 0.498 90)
			(size 0.25 0.55)
			(layers "F.Cu" "F.Mask" "F.Paste")
			(roundrect_rratio 0.25)
			(net 513 "/USB Hub/USBC3_RX_{1}+")
			(pintype "passive")
		)
		(pad "5" smd roundrect
			(at -0.387 0.998 90)
			(size 0.25 0.55)
			(layers "F.Cu" "F.Mask" "F.Paste")
			(roundrect_rratio 0.25)
			(net 507 "/USB Hub/USBC3_RX_{1}-")
			(pintype "passive")
		)
		(pad "6" smd roundrect
			(at 0.385 0.998 90)
			(size 0.25 0.55)
			(layers "F.Cu" "F.Mask" "F.Paste")
			(roundrect_rratio 0.25)
			(net 507 "/USB Hub/USBC3_RX_{1}-")
			(pintype "passive")
		)
		(pad "7" smd roundrect
			(at 0.385 0.498 90)
			(size 0.25 0.55)
			(layers "F.Cu" "F.Mask" "F.Paste")
			(roundrect_rratio 0.25)
			(net 513 "/USB Hub/USBC3_RX_{1}+")
			(pintype "passive")
		)
		(pad "8" smd roundrect
			(at 0.385 0 90)
			(size 0.4 0.55)
			(layers "F.Cu" "F.Mask" "F.Paste")
			(roundrect_rratio 0.25)
			(net 1 "GND")
			(pintype "passive")
		)
		(pad "9" smd roundrect
			(at 0.385 -0.5 90)
			(size 0.25 0.55)
			(layers "F.Cu" "F.Mask" "F.Paste")
			(roundrect_rratio 0.25)
			(net 164 "/USB Hub/USBC3_CONN_TX1_P")
			(pintype "passive")
		)
		(pad "10" smd roundrect
			(at 0.385 -1 90)
			(size 0.25 0.55)
			(layers "F.Cu" "F.Mask" "F.Paste")
			(roundrect_rratio 0.25)
			(net 95 "/USB Hub/USBC3_CONN_TX1_N")
			(pintype "passive")
		)
	)
	(footprint "antmicro-footprints:SOD-523"
		(layer "F.Cu")
		(at 111.22 59.79 90)
		(property "Reference" "D62"
			(at -1.6 -3.66 90)
			(layer "F.SilkS")
			(effects
				(font
					(size 0.7 0.7)
					(thickness 0.15)
				)
				(justify left bottom)
			)
		)
		(property "Value" "PESD5Z5.0F"
			(at 0 1.499 90)
			(layer "F.Fab")
			(effects
				(font
					(size 0.7 0.7)
					(thickness 0.15)
				)
				(justify left bottom)
			)
		)
		(property "Datasheet" "https://assets.nexperia.com/documents/data-sheet/PESD5Z5_0.pdf"
			(at 0 0 90)
			(layer "F.Fab")
			(hide yes)
			(effects
				(font
					(size 1.27 1.27)
					(thickness 0.15)
				)
			)
		)
		(property "Description" "Unidirectional TVS, 30 kV,  SOD-523, 5 V, 89 pF"
			(at 0 0 90)
			(layer "F.Fab")
			(hide yes)
			(effects
				(font
					(size 1.27 1.27)
					(thickness 0.15)
				)
			)
		)
		(property "Manufacturer" "Nexperia"
			(at 0 0 90)
			(unlocked yes)
			(layer "F.Fab")
			(hide yes)
			(effects
				(font
					(size 1 1)
					(thickness 0.15)
				)
			)
		)
		(property "MPN" "PESD5Z5.0F"
			(at 0 0 90)
			(unlocked yes)
			(layer "F.Fab")
			(hide yes)
			(effects
				(font
					(size 1 1)
					(thickness 0.15)
				)
			)
		)
		(property "Author" "Antmicro"
			(at 0 0 90)
			(unlocked yes)
			(layer "F.Fab")
			(hide yes)
			(effects
				(font
					(size 1 1)
					(thickness 0.15)
				)
			)
		)
		(property "License" "Apache-2.0"
			(at 0 0 90)
			(unlocked yes)
			(layer "F.Fab")
			(hide yes)
			(effects
				(font
					(size 1 1)
					(thickness 0.15)
				)
			)
		)
		(sheetname "/DCDC/")
		(sheetfile "dcdc.kicad_sch")
		(attr smd)
		(fp_line
			(start -0.35 -0.5)
			(end -0.35 0.5)
			(stroke
				(width 0.15)
				(type solid)
			)
			(layer "F.SilkS")
		)
		(fp_poly
			(pts
				(xy -1 -0.6) (xy 1 -0.6) (xy 1 0.6) (xy -1 0.6)
			)
			(stroke
				(width 0.05)
				(type solid)
			)
			(fill no)
			(layer "F.CrtYd")
		)
		(fp_line
			(start 0.65 -0.425)
			(end 0.65 0.423)
			(stroke
				(width 0.15)
				(type solid)
			)
			(layer "F.Fab")
		)
		(fp_line
			(start -0.652 -0.425)
			(end 0.65 -0.425)
			(stroke
				(width 0.15)
				(type solid)
			)
			(layer "F.Fab")
		)
		(fp_line
			(start -0.35 -0.4)
			(end -0.35 0.4)
			(stroke
				(width 0.15)
				(type solid)
			)
			(layer "F.Fab")
		)
		(fp_line
			(start -0.652 0.423)
			(end -0.652 -0.425)
			(stroke
				(width 0.15)
				(type solid)
			)
			(layer "F.Fab")
		)
		(fp_line
			(start -0.652 0.423)
			(end 0.65 0.423)
			(stroke
				(width 0.15)
				(type solid)
			)
			(layer "F.Fab")
		)
		(fp_text user "Author: Antmicro"
			(at -1.276 4.7 90)
			(layer "F.Fab")
			(effects
				(font
					(size 0.7 0.7)
					(thickness 0.15)
				)
				(justify left bottom)
			)
		)
		(fp_text user "License: Apache-2.0"
			(at -1.276 5.9 90)
			(layer "F.Fab")
			(effects
				(font
					(size 0.7 0.7)
					(thickness 0.15)
				)
				(justify left bottom)
			)
		)
		(fp_text user "${REFERENCE}"
			(at -1.276 3.499 90)
			(layer "F.Fab")
			(effects
				(font
					(size 0.7 0.7)
					(thickness 0.15)
				)
				(justify left bottom)
			)
		)
		(pad "1" smd roundrect
			(at -0.701 0 90)
			(size 0.5 0.6)
			(layers "F.Cu" "F.Mask" "F.Paste")
			(roundrect_rratio 0.25)
			(net 491 "+5V_AON")
			(pinfunction "C")
			(pintype "passive")
		)
		(pad "2" smd roundrect
			(at 0.699001 0 90)
			(size 0.5 0.6)
			(layers "F.Cu" "F.Mask" "F.Paste")
			(roundrect_rratio 0.25)
			(net 1 "GND")
			(pinfunction "A")
			(pintype "passive")
		)
	)
	(footprint "antmicro-footprints:R_0402_1005Metric"
		(layer "F.Cu")
		(at 162.709468 78.1 90)
		(descr "Resistor SMD 0402")
		(tags "resistor SMD 0402")
		(property "Reference" "R365"
			(at -1 -1.809468 90)
			(layer "F.SilkS")
			(effects
				(font
					(size 0.7 0.7)
					(thickness 0.15)
				)
				(justify left bottom)
			)
		)
		(property "Value" "R_27R_0402"
			(at -1.011843 1.772047 90)
			(layer "F.Fab")
			(effects
				(font
					(size 0.7 0.7)
					(thickness 0.15)
				)
				(justify left bottom)
			)
		)
		(property "Datasheet" "https://www.bourns.com/docs/product-datasheets/cr.pdf"
			(at 0 0 90)
			(layer "F.Fab")
			(hide yes)
			(effects
				(font
					(size 1.27 1.27)
					(thickness 0.15)
				)
			)
		)
		(property "Description" "SMD Chip Resistor, 27 ohm, ± 1%, 63 mW, 0402 [1005 Metric], Thick Film, General Purpose"
			(at 0 0 90)
			(layer "F.Fab")
			(hide yes)
			(effects
				(font
					(size 1.27 1.27)
					(thickness 0.15)
				)
			)
		)
		(property "Manufacturer" "Bourns"
			(at 0 0 90)
			(unlocked yes)
			(layer "F.Fab")
			(hide yes)
			(effects
				(font
					(size 1 1)
					(thickness 0.15)
				)
			)
		)
		(property "MPN" "CR0402-FX-27R0GLF"
			(at 0 0 90)
			(unlocked yes)
			(layer "F.Fab")
			(hide yes)
			(effects
				(font
					(size 1 1)
					(thickness 0.15)
				)
			)
		)
		(property "Val" "27R"
			(at 0 0 90)
			(unlocked yes)
			(layer "F.Fab")
			(hide yes)
			(effects
				(font
					(size 1 1)
					(thickness 0.15)
				)
			)
		)
		(property "License" "Apache-2.0"
			(at 0 0 90)
			(unlocked yes)
			(layer "F.Fab")
			(hide yes)
			(effects
				(font
					(size 1 1)
					(thickness 0.15)
				)
			)
		)
		(property "Author" "Antmicro"
			(at 0 0 90)
			(unlocked yes)
			(layer "F.Fab")
			(hide yes)
			(effects
				(font
					(size 1 1)
					(thickness 0.15)
				)
			)
		)
		(property "Tolerance" "1%"
			(at 0 0 90)
			(unlocked yes)
			(layer "F.Fab")
			(hide yes)
			(effects
				(font
					(size 1 1)
					(thickness 0.15)
				)
			)
		)
		(component_classes
			(class "DCDC_20V")
		)
		(sheetname "/DCDC/")
		(sheetfile "dcdc.kicad_sch")
		(attr smd)
		(fp_rect
			(start -0.925 -0.47)
			(end 0.925 0.47)
			(stroke
				(width 0.05)
				(type default)
			)
			(fill no)
			(layer "F.CrtYd")
		)
		(fp_rect
			(start -0.5 -0.25)
			(end 0.5 0.25)
			(stroke
				(width 0.15)
				(type solid)
			)
			(fill no)
			(layer "F.Fab")
		)
		(fp_text user "License: Apache-2.0"
			(at -0.95 5.169 90)
			(layer "F.Fab")
			(effects
				(font
					(size 0.7 0.7)
					(thickness 0.15)
				)
				(justify left bottom)
			)
		)
		(fp_text user "${REFERENCE}"
			(at -0.95 3.168 90)
			(layer "F.Fab")
			(effects
				(font
					(size 0.7 0.7)
					(thickness 0.15)
				)
				(justify left bottom)
			)
		)
		(fp_text user "Author: Antmicro"
			(at -0.95 4.169 90)
			(layer "F.Fab")
			(effects
				(font
					(size 0.7 0.7)
					(thickness 0.15)
				)
				(justify left bottom)
			)
		)
		(pad "1" smd roundrect
			(at -0.48 0 90)
			(size 0.59 0.64)
			(layers "F.Cu" "F.Mask" "F.Paste")
			(roundrect_rratio 0.25)
			(net 1284 "Net-(U66-IN+)")
			(pintype "passive")
		)
		(pad "2" smd roundrect
			(at 0.48 0 90)
			(size 0.59 0.64)
			(layers "F.Cu" "F.Mask" "F.Paste")
			(roundrect_rratio 0.25)
			(net 1105 "/DCDC/20V_OUT")
			(pintype "passive")
		)
	)
	(footprint "antmicro-footprints:C_0402_1005Metric"
		(layer "F.Cu")
		(at 217.6 84.3 -90)
		(descr "Capacitor SMD 0402")
		(tags "capacitor SMD 0402")
		(property "Reference" "C124"
			(at -3.7 0.4 90)
			(layer "F.SilkS")
			(effects
				(font
					(size 0.7 0.7)
					(thickness 0.15)
				)
				(justify right top)
			)
		)
		(property "Value" "C_10u_0402"
			(at -1.022927 2.155213 90)
			(layer "F.Fab")
			(effects
				(font
					(size 0.7 0.7)
					(thickness 0.15)
				)
				(justify right top)
			)
		)
		(property "Datasheet" "https://www.yageo.com/en/Chart/Download/pdf/CC0402MRX5R5BB106"
			(at 0 0 90)
			(layer "F.Fab")
			(hide yes)
			(effects
				(font
					(size 1.27 1.27)
					(thickness 0.15)
				)
			)
		)
		(property "Description" "SMD Multilayer Ceramic Capacitor, 10 µF, 6.3 V, 0402 [1005 Metric], ± 20%, X5R, CC Series"
			(at 0 0 90)
			(layer "F.Fab")
			(hide yes)
			(effects
				(font
					(size 1.27 1.27)
					(thickness 0.15)
				)
			)
		)
		(property "MPN" "CC0402MRX5R5BB106"
			(at 0 0 270)
			(unlocked yes)
			(layer "F.Fab")
			(hide yes)
			(effects
				(font
					(size 1 1)
					(thickness 0.15)
				)
			)
		)
		(property "Manufacturer" "YAGEO"
			(at 0 0 270)
			(unlocked yes)
			(layer "F.Fab")
			(hide yes)
			(effects
				(font
					(size 1 1)
					(thickness 0.15)
				)
			)
		)
		(property "License" "Apache-2.0"
			(at 0 0 270)
			(unlocked yes)
			(layer "F.Fab")
			(hide yes)
			(effects
				(font
					(size 1 1)
					(thickness 0.15)
				)
			)
		)
		(property "Author" "Antmicro"
			(at 0 0 270)
			(unlocked yes)
			(layer "F.Fab")
			(hide yes)
			(effects
				(font
					(size 1 1)
					(thickness 0.15)
				)
			)
		)
		(property "Val" "10u"
			(at 0 0 270)
			(unlocked yes)
			(layer "F.Fab")
			(hide yes)
			(effects
				(font
					(size 1 1)
					(thickness 0.15)
				)
			)
		)
		(property "Voltage" ""
			(at 0 0 270)
			(unlocked yes)
			(layer "F.Fab")
			(hide yes)
			(effects
				(font
					(size 1 1)
					(thickness 0.15)
				)
			)
		)
		(property "Dielectric" ""
			(at 0 0 270)
			(unlocked yes)
			(layer "F.Fab")
			(hide yes)
			(effects
				(font
					(size 1 1)
					(thickness 0.15)
				)
			)
		)
		(sheetname "/USB DP Alt mode/")
		(sheetfile "usb_dp.kicad_sch")
		(attr smd)
		(fp_rect
			(start -0.925 -0.47)
			(end 0.925 0.47)
			(stroke
				(width 0.05)
				(type default)
			)
			(fill no)
			(layer "F.CrtYd")
		)
		(fp_line
			(start -0.494 0.248)
			(end -0.494 -0.25)
			(stroke
				(width 0.15)
				(type solid)
			)
			(layer "F.Fab")
		)
		(fp_line
			(start 0.504 0.248)
			(end -0.494 0.248)
			(stroke
				(width 0.15)
				(type solid)
			)
			(layer "F.Fab")
		)
		(fp_line
			(start -0.494 -0.25)
			(end 0.504 -0.25)
			(stroke
				(width 0.15)
				(type solid)
			)
			(layer "F.Fab")
		)
		(fp_line
			(start 0.504 -0.25)
			(end 0.504 0.248)
			(stroke
				(width 0.15)
				(type solid)
			)
			(layer "F.Fab")
		)
		(fp_text user "${REFERENCE}"
			(at -0.939 4.599 90)
			(layer "F.Fab")
			(effects
				(font
					(size 0.7 0.7)
					(thickness 0.15)
				)
				(justify right top)
			)
		)
		(fp_text user "License: Apache-2.0"
			(at -0.939 5.799 90)
			(layer "F.Fab")
			(effects
				(font
					(size 0.7 0.7)
					(thickness 0.15)
				)
				(justify right top)
			)
		)
		(fp_text user "Author: Antmicro"
			(at -0.939 3.399 90)
			(layer "F.Fab")
			(effects
				(font
					(size 0.7 0.7)
					(thickness 0.15)
				)
				(justify right top)
			)
		)
		(pad "1" smd roundrect
			(at -0.48 0 270)
			(size 0.59 0.64)
			(layers "F.Cu" "F.Mask" "F.Paste")
			(roundrect_rratio 0.25)
			(net 1 "GND")
			(pintype "passive")
		)
		(pad "2" smd roundrect
			(at 0.48 0 270)
			(size 0.59 0.64)
			(layers "F.Cu" "F.Mask" "F.Paste")
			(roundrect_rratio 0.25)
			(net 2 "+3V3")
			(pintype "passive")
		)
	)
)
